# T6G (Grand Teton) — schematic netlist excerpt (pin names and nets, part order shuffled) for the footprints in the layout excerpt that follows; sources: Cadence DE-HDL packaged netlist, KiCad conversion of 04192023_DAF0TMB3IC0_F0TG_MB_C_brd_V02_OCP.brd

PC6567_1  Q_CAP  22UF 4V 20% X6S  pkg C0805  page 363 : A = P0V9_CPU0_RT_2D ; B = GND
C6032  Q_CAP  0.1UF 25V 10% X7R  pkg 0402  page 177 : A = P1V2_CPU0_USB_DVDD12 ; B = GND
PC6816  Q_CAP  22UF 16V 20% X6S  pkg C0805  page 363 : A = SW_P12V_AUX_P0V9_RETIMER_CPU0_FLT ; B = GND
R1403  Q_RES  4.7K 5% CHIP  pkg 0201LF  page 185 : A = P1V8_CPU1_RT_1D ; B = SMB_RT_CPU1_P2_ROM_MUX_2D_R_SDA

(kicad_pcb
	(version 20260206)
	(generator "pcbnew")
	(generator_version "10.0")
	(general
		(thickness 1.6)
		(legacy_teardrops no)
	)
	(paper "A4")
	(title_block
		(title "04192023_DAF0TMB3IC0_F0TG_MB_C_brd_V02_OCP.brd")
		(comment 1 "Grand Teton / footprints 7713-7716 of 8354")
	)
	(layers
		(0 "F.Cu" signal "TOP")
		(4 "In1.Cu" signal "GND")
		(6 "In2.Cu" signal "IN1")
		(8 "In3.Cu" signal "GND1")
		(10 "In4.Cu" signal "IN2")
		(12 "In5.Cu" signal "GND2")
		(14 "In6.Cu" signal "IN3")
		(16 "In7.Cu" signal "GND3")
		(18 "In8.Cu" signal "VCC")
		(20 "In9.Cu" signal "VCC1")
		(22 "In10.Cu" signal "GND4")
		(24 "In11.Cu" signal "IN4")
		(26 "In12.Cu" signal "GND5")
		(28 "In13.Cu" signal "IN5")
		(30 "In14.Cu" signal "GND6")
		(32 "In15.Cu" signal "IN6")
		(34 "In16.Cu" signal "GND7")
		(2 "B.Cu" signal "BOTTOM")
		(9 "F.Adhes" user "F.Adhesive")
		(11 "B.Adhes" user "B.Adhesive")
		(13 "F.Paste" user "Package Geometry/Pastemask Top")
		(15 "B.Paste" user "Package Geometry/Pastemask Bottom")
		(5 "F.SilkS" user "Ref Des/Silkscreen Top")
		(7 "B.SilkS" user "Ref Des/Silkscreen Bottom")
		(1 "F.Mask" user "Board Geometry/Soldermask Top")
		(3 "B.Mask" user "Board Geometry/Soldermask Bottom")
		(17 "Dwgs.User" user "User.Drawings")
		(19 "Cmts.User" user "User.Comments")
		(21 "Eco1.User" user "User.Eco1")
		(23 "Eco2.User" user "User.Eco2")
		(25 "Edge.Cuts" user "Board Geometry/Outline")
		(27 "Margin" user)
		(31 "F.CrtYd" user "Package Geometry/Place Bound Top")
		(29 "B.CrtYd" user "Package Geometry/Place Bound Bottom")
		(35 "F.Fab" user "Ref Des/Assembly Top")
		(33 "B.Fab" user "Ref Des/Assembly Bottom")
	)
	(footprint ""
		(layer "B.Cu")
		(at 133.506972 -41.007792 90)
		(property "Reference" "C6032"
			(at 0 0 90)
			(layer "B.SilkS")
			(hide yes)
			(effects
				(font
					(size 1.27 1.27)
				)
				(justify mirror)
			)
		)
		(property "Value" ""
			(at 0 0 90)
			(layer "B.Fab")
			(effects
				(font
					(size 1.27 1.27)
				)
				(justify mirror)
			)
		)
		(duplicate_pad_numbers_are_jumpers no)
		(fp_line
			(start 0.7874 -0.4064)
			(end -0.7874 -0.4064)
			(stroke
				(width 0.1524)
				(type default)
			)
			(layer "B.SilkS")
		)
		(fp_line
			(start -0.7874 -0.4064)
			(end -0.7874 0.4064)
			(stroke
				(width 0.1524)
				(type default)
			)
			(layer "B.SilkS")
		)
		(fp_line
			(start 0.7874 0.4064)
			(end 0.7874 -0.4064)
			(stroke
				(width 0.1524)
				(type default)
			)
			(layer "B.SilkS")
		)
		(fp_line
			(start -0.7874 0.4064)
			(end 0.7874 0.4064)
			(stroke
				(width 0.1524)
				(type default)
			)
			(layer "B.SilkS")
		)
		(fp_line
			(start 0.67945 -0.305054)
			(end 0.12065 -0.305054)
			(stroke
				(width 0.1)
				(type default)
			)
			(layer "B.Fab")
		)
		(fp_line
			(start 0.12065 -0.305054)
			(end 0.12065 -0.2794)
			(stroke
				(width 0.1)
				(type default)
			)
			(layer "B.Fab")
		)
		(fp_line
			(start -0.12065 -0.3048)
			(end -0.67945 -0.3048)
			(stroke
				(width 0.1)
				(type default)
			)
			(layer "B.Fab")
		)
		(fp_line
			(start -0.67945 -0.3048)
			(end -0.67945 0.3048)
			(stroke
				(width 0.1)
				(type default)
			)
			(layer "B.Fab")
		)
		(fp_line
			(start 0.12065 -0.2794)
			(end -0.12065 -0.2794)
			(stroke
				(width 0.1)
				(type default)
			)
			(layer "B.Fab")
		)
		(fp_line
			(start -0.12065 -0.2794)
			(end -0.12065 -0.3048)
			(stroke
				(width 0.1)
				(type default)
			)
			(layer "B.Fab")
		)
		(fp_line
			(start 0.12065 0.2794)
			(end 0.12065 0.3048)
			(stroke
				(width 0.1)
				(type default)
			)
			(layer "B.Fab")
		)
		(fp_line
			(start -0.120396 0.2794)
			(end 0.12065 0.2794)
			(stroke
				(width 0.1)
				(type default)
			)
			(layer "B.Fab")
		)
		(fp_line
			(start 0.67945 0.3048)
			(end 0.67945 -0.305054)
			(stroke
				(width 0.1)
				(type default)
			)
			(layer "B.Fab")
		)
		(fp_line
			(start 0.12065 0.3048)
			(end 0.67945 0.3048)
			(stroke
				(width 0.1)
				(type default)
			)
			(layer "B.Fab")
		)
		(fp_line
			(start -0.120396 0.3048)
			(end -0.120396 0.2794)
			(stroke
				(width 0.1)
				(type default)
			)
			(layer "B.Fab")
		)
		(fp_line
			(start -0.67945 0.3048)
			(end -0.120396 0.3048)
			(stroke
				(width 0.1)
				(type default)
			)
			(layer "B.Fab")
		)
		(pad "1" smd circle
			(at 0.40005 0 270)
			(size 0 0)
			(layers "B.Cu" "B.Mask" "B.Paste")
			(net "P1V2_CPU0_USB_DVDD12")
		)
		(pad "2" smd circle
			(at -0.40005 0 270)
			(size 0 0)
			(layers "B.Cu" "B.Mask" "B.Paste")
			(net "GND")
		)
	)
	(footprint ""
		(layer "B.Cu")
		(at 461.498188 -389.132064 -90)
		(property "Reference" "PC6567_1"
			(at 0 0 90)
			(layer "B.SilkS")
			(hide yes)
			(effects
				(font
					(size 1.27 1.27)
				)
				(justify mirror)
			)
		)
		(property "Value" ""
			(at 0 0 90)
			(layer "B.Fab")
			(effects
				(font
					(size 1.27 1.27)
				)
				(justify mirror)
			)
		)
		(duplicate_pad_numbers_are_jumpers no)
		(fp_line
			(start -1.524 0.762)
			(end 1.524 0.762)
			(stroke
				(width 0.1524)
				(type default)
			)
			(layer "B.SilkS")
		)
		(fp_line
			(start 1.524 0.762)
			(end 1.524 -0.762)
			(stroke
				(width 0.1524)
				(type default)
			)
			(layer "B.SilkS")
		)
		(fp_line
			(start -1.524 -0.762)
			(end -1.524 0.762)
			(stroke
				(width 0.1524)
				(type default)
			)
			(layer "B.SilkS")
		)
		(fp_line
			(start 1.524 -0.762)
			(end -1.524 -0.762)
			(stroke
				(width 0.1524)
				(type default)
			)
			(layer "B.SilkS")
		)
		(fp_line
			(start -1.1049 0.724916)
			(end -1.1049 -0.724916)
			(stroke
				(width 0.1)
				(type default)
			)
			(layer "B.Fab")
		)
		(fp_line
			(start 1.1049 0.724916)
			(end -1.1049 0.724916)
			(stroke
				(width 0.1)
				(type default)
			)
			(layer "B.Fab")
		)
		(fp_line
			(start -1.1049 -0.724916)
			(end 1.1049 -0.724916)
			(stroke
				(width 0.1)
				(type default)
			)
			(layer "B.Fab")
		)
		(fp_line
			(start 1.1049 -0.724916)
			(end 1.1049 0.724916)
			(stroke
				(width 0.1)
				(type default)
			)
			(layer "B.Fab")
		)
		(pad "1" smd rect
			(at 0.889 0 270)
			(size 1.016 1.27)
			(layers "B.Cu" "B.Mask" "B.Paste")
			(net "P0V9_CPU0_RT_2D")
		)
		(pad "2" smd rect
			(at -0.889 0 270)
			(size 1.016 1.27)
			(layers "B.Cu" "B.Mask" "B.Paste")
			(net "GND")
		)
	)
	(footprint ""
		(layer "B.Cu")
		(at 447.237866 -407.6573)
		(property "Reference" "PC6816"
			(at 0 0 0)
			(layer "B.SilkS")
			(hide yes)
			(effects
				(font
					(size 1.27 1.27)
				)
				(justify mirror)
			)
		)
		(property "Value" ""
			(at 0 0 0)
			(layer "B.Fab")
			(effects
				(font
					(size 1.27 1.27)
				)
				(justify mirror)
			)
		)
		(duplicate_pad_numbers_are_jumpers no)
		(fp_line
			(start -1.524 -0.762)
			(end -1.524 0.762)
			(stroke
				(width 0.1524)
				(type default)
			)
			(layer "B.SilkS")
		)
		(fp_line
			(start -1.524 0.762)
			(end 1.524 0.762)
			(stroke
				(width 0.1524)
				(type default)
			)
			(layer "B.SilkS")
		)
		(fp_line
			(start 1.524 -0.762)
			(end -1.524 -0.762)
			(stroke
				(width 0.1524)
				(type default)
			)
			(layer "B.SilkS")
		)
		(fp_line
			(start 1.524 0.762)
			(end 1.524 -0.762)
			(stroke
				(width 0.1524)
				(type default)
			)
			(layer "B.SilkS")
		)
		(fp_line
			(start -1.1049 -0.724916)
			(end 1.1049 -0.724916)
			(stroke
				(width 0.1)
				(type default)
			)
			(layer "B.Fab")
		)
		(fp_line
			(start -1.1049 0.724916)
			(end -1.1049 -0.724916)
			(stroke
				(width 0.1)
				(type default)
			)
			(layer "B.Fab")
		)
		(fp_line
			(start 1.1049 -0.724916)
			(end 1.1049 0.724916)
			(stroke
				(width 0.1)
				(type default)
			)
			(layer "B.Fab")
		)
		(fp_line
			(start 1.1049 0.724916)
			(end -1.1049 0.724916)
			(stroke
				(width 0.1)
				(type default)
			)
			(layer "B.Fab")
		)
		(pad "1" smd rect
			(at 0.889 0)
			(size 1.016 1.27)
			(layers "B.Cu" "B.Mask" "B.Paste")
			(net "SW_P12V_AUX_P0V9_RETIMER_CPU0_FLT")
		)
		(pad "2" smd rect
			(at -0.889 0)
			(size 1.016 1.27)
			(layers "B.Cu" "B.Mask" "B.Paste")
			(net "GND")
		)
	)
	(footprint ""
		(layer "B.Cu")
		(at 239.903 -340.741)
		(property "Reference" "R1403"
			(at 0 0 0)
			(layer "B.SilkS")
			(hide yes)
			(effects
				(font
					(size 1.27 1.27)
				)
				(justify mirror)
			)
		)
		(property "Value" ""
			(at 0 0 0)
			(layer "B.Fab")
			(effects
				(font
					(size 1.27 1.27)
				)
				(justify mirror)
			)
		)
		(duplicate_pad_numbers_are_jumpers no)
		(fp_line
			(start -0.32512 -0.175006)
			(end -0.32512 0.175006)
			(stroke
				(width 0.1)
				(type default)
			)
			(layer "B.Fab")
		)
		(fp_line
			(start -0.32512 0.175006)
			(end 0.32512 0.175006)
			(stroke
				(width 0.1)
				(type default)
			)
			(layer "B.Fab")
		)
		(fp_line
			(start 0.32512 -0.175006)
			(end -0.32512 -0.175006)
			(stroke
				(width 0.1)
				(type default)
			)
			(layer "B.Fab")
		)
		(fp_line
			(start 0.32512 0.175006)
			(end 0.32512 -0.175006)
			(stroke
				(width 0.1)
				(type default)
			)
			(layer "B.Fab")
		)
		(pad "1" smd rect
			(at 0.2667 0 180)
			(size 0.3048 0.381)
			(layers "B.Cu" "B.Mask" "B.Paste")
			(net "P1V8_CPU1_RT_1D")
		)
		(pad "2" smd rect
			(at -0.2667 0)
			(size 0.3048 0.381)
			(layers "B.Cu" "B.Mask" "B.Paste")
			(net "SMB_RT_CPU1_P2_ROM_MUX_2D_R_SDA")
		)
	)
)
